# T6G (Grand Teton) — schematic netlist excerpt (pin names and nets, part order shuffled) for the footprints in the layout excerpt that follows; sources: Cadence DE-HDL packaged netlist, KiCad conversion of 04192023_DAF0TMB3IC0_F0TG_MB_C_brd_V02_OCP.brd

L30  Q_INDUCTOR  BLM15PD121SN1D/1300MA IND  pkg SMLF  page 312 : \1\ = P1V8_CPU0_RT_1D ; \2\ = P1V8_CPU0_RT3_1A_1D
R8117  Q_RES  1M 1% CHIP  pkg 0402LF  page 268 : A = P12V_AUX_UV_ADR_TRIGGER ; B = FM_UV_ADR_TRIGGER_N_R2

(kicad_pcb
	(version 20260206)
	(generator "pcbnew")
	(generator_version "10.0")
	(general
		(thickness 1.6)
		(legacy_teardrops no)
	)
	(paper "A4")
	(title_block
		(title "04192023_DAF0TMB3IC0_F0TG_MB_C_brd_V02_OCP.brd")
		(comment 1 "Grand Teton / footprints 1173-1174 of 8354")
	)
	(layers
		(0 "F.Cu" signal "TOP")
		(4 "In1.Cu" signal "GND")
		(6 "In2.Cu" signal "IN1")
		(8 "In3.Cu" signal "GND1")
		(10 "In4.Cu" signal "IN2")
		(12 "In5.Cu" signal "GND2")
		(14 "In6.Cu" signal "IN3")
		(16 "In7.Cu" signal "GND3")
		(18 "In8.Cu" signal "VCC")
		(20 "In9.Cu" signal "VCC1")
		(22 "In10.Cu" signal "GND4")
		(24 "In11.Cu" signal "IN4")
		(26 "In12.Cu" signal "GND5")
		(28 "In13.Cu" signal "IN5")
		(30 "In14.Cu" signal "GND6")
		(32 "In15.Cu" signal "IN6")
		(34 "In16.Cu" signal "GND7")
		(2 "B.Cu" signal "BOTTOM")
		(9 "F.Adhes" user "F.Adhesive")
		(11 "B.Adhes" user "B.Adhesive")
		(13 "F.Paste" user "Package Geometry/Pastemask Top")
		(15 "B.Paste" user "Package Geometry/Pastemask Bottom")
		(5 "F.SilkS" user "Ref Des/Silkscreen Top")
		(7 "B.SilkS" user "Ref Des/Silkscreen Bottom")
		(1 "F.Mask" user "Board Geometry/Soldermask Top")
		(3 "B.Mask" user "Board Geometry/Soldermask Bottom")
		(17 "Dwgs.User" user "User.Drawings")
		(19 "Cmts.User" user "User.Comments")
		(21 "Eco1.User" user "User.Eco1")
		(23 "Eco2.User" user "User.Eco2")
		(25 "Edge.Cuts" user "Board Geometry/Outline")
		(27 "Margin" user)
		(31 "F.CrtYd" user "Package Geometry/Place Bound Top")
		(29 "B.CrtYd" user "Package Geometry/Place Bound Bottom")
		(35 "F.Fab" user "Ref Des/Assembly Top")
		(33 "B.Fab" user "Ref Des/Assembly Bottom")
	)
	(footprint ""
		(layer "F.Cu")
		(at 134.112 -109.855)
		(property "Reference" "R8117"
			(at 0 0 0)
			(layer "F.SilkS")
			(hide yes)
			(effects
				(font
					(size 1.27 1.27)
				)
			)
		)
		(property "Value" ""
			(at 0 0 0)
			(layer "F.Fab")
			(effects
				(font
					(size 1.27 1.27)
				)
			)
		)
		(duplicate_pad_numbers_are_jumpers no)
		(fp_line
			(start -0.7874 -0.4064)
			(end 0.7874 -0.4064)
			(stroke
				(width 0.1524)
				(type default)
			)
			(layer "F.SilkS")
		)
		(fp_line
			(start -0.7874 0.4064)
			(end -0.7874 -0.4064)
			(stroke
				(width 0.1524)
				(type default)
			)
			(layer "F.SilkS")
		)
		(fp_line
			(start 0.7874 -0.4064)
			(end 0.7874 0.4064)
			(stroke
				(width 0.1524)
				(type default)
			)
			(layer "F.SilkS")
		)
		(fp_line
			(start 0.7874 0.4064)
			(end -0.7874 0.4064)
			(stroke
				(width 0.1524)
				(type default)
			)
			(layer "F.SilkS")
		)
		(fp_line
			(start -0.67945 -0.305054)
			(end -0.12065 -0.305054)
			(stroke
				(width 0.1)
				(type default)
			)
			(layer "F.Fab")
		)
		(fp_line
			(start -0.67945 0.3048)
			(end -0.67945 -0.305054)
			(stroke
				(width 0.1)
				(type default)
			)
			(layer "F.Fab")
		)
		(fp_line
			(start -0.12065 -0.305054)
			(end -0.12065 -0.2794)
			(stroke
				(width 0.1)
				(type default)
			)
			(layer "F.Fab")
		)
		(fp_line
			(start -0.12065 -0.2794)
			(end 0.12065 -0.2794)
			(stroke
				(width 0.1)
				(type default)
			)
			(layer "F.Fab")
		)
		(fp_line
			(start -0.12065 0.2794)
			(end -0.12065 0.3048)
			(stroke
				(width 0.1)
				(type default)
			)
			(layer "F.Fab")
		)
		(fp_line
			(start -0.12065 0.3048)
			(end -0.67945 0.3048)
			(stroke
				(width 0.1)
				(type default)
			)
			(layer "F.Fab")
		)
		(fp_line
			(start 0.120396 0.2794)
			(end -0.12065 0.2794)
			(stroke
				(width 0.1)
				(type default)
			)
			(layer "F.Fab")
		)
		(fp_line
			(start 0.120396 0.3048)
			(end 0.120396 0.2794)
			(stroke
				(width 0.1)
				(type default)
			)
			(layer "F.Fab")
		)
		(fp_line
			(start 0.12065 -0.3048)
			(end 0.67945 -0.3048)
			(stroke
				(width 0.1)
				(type default)
			)
			(layer "F.Fab")
		)
		(fp_line
			(start 0.12065 -0.2794)
			(end 0.12065 -0.3048)
			(stroke
				(width 0.1)
				(type default)
			)
			(layer "F.Fab")
		)
		(fp_line
			(start 0.67945 -0.3048)
			(end 0.67945 0.3048)
			(stroke
				(width 0.1)
				(type default)
			)
			(layer "F.Fab")
		)
		(fp_line
			(start 0.67945 0.3048)
			(end 0.120396 0.3048)
			(stroke
				(width 0.1)
				(type default)
			)
			(layer "F.Fab")
		)
		(pad "1" smd circle
			(at -0.40005 0)
			(size 0 0)
			(layers "F.Cu" "F.Mask" "F.Paste")
			(net "P12V_AUX_UV_ADR_TRIGGER")
		)
		(pad "2" smd circle
			(at 0.40005 0)
			(size 0 0)
			(layers "F.Cu" "F.Mask" "F.Paste")
			(net "FM_UV_ADR_TRIGGER_N_R2")
		)
	)
	(footprint ""
		(layer "F.Cu")
		(at 393.762484 -393.47648 180)
		(property "Reference" "L30"
			(at 0 0 180)
			(layer "F.SilkS")
			(hide yes)
			(effects
				(font
					(size 1.27 1.27)
				)
			)
		)
		(property "Value" ""
			(at 0 0 180)
			(layer "F.Fab")
			(effects
				(font
					(size 1.27 1.27)
				)
			)
		)
		(duplicate_pad_numbers_are_jumpers no)
		(fp_line
			(start 0.762 0.381)
			(end -0.762 0.381)
			(stroke
				(width 0.1524)
				(type default)
			)
			(layer "F.SilkS")
		)
		(fp_line
			(start 0.762 -0.381)
			(end 0.762 0.381)
			(stroke
				(width 0.1524)
				(type default)
			)
			(layer "F.SilkS")
		)
		(fp_line
			(start -0.762 0.381)
			(end -0.762 -0.381)
			(stroke
				(width 0.1524)
				(type default)
			)
			(layer "F.SilkS")
		)
		(fp_line
			(start -0.762 -0.381)
			(end 0.762 -0.381)
			(stroke
				(width 0.1524)
				(type default)
			)
			(layer "F.SilkS")
		)
		(fp_line
			(start 0.680466 0.306324)
			(end 0.118364 0.306324)
			(stroke
				(width 0.1)
				(type default)
			)
			(layer "F.Fab")
		)
		(fp_line
			(start 0.680466 -0.306324)
			(end 0.680466 0.306324)
			(stroke
				(width 0.1)
				(type default)
			)
			(layer "F.Fab")
		)
		(fp_line
			(start 0.118872 -0.2794)
			(end 0.118872 -0.306324)
			(stroke
				(width 0.1)
				(type default)
			)
			(layer "F.Fab")
		)
		(fp_line
			(start 0.118872 -0.306324)
			(end 0.680466 -0.306324)
			(stroke
				(width 0.1)
				(type default)
			)
			(layer "F.Fab")
		)
		(fp_line
			(start 0.118364 0.306324)
			(end 0.118364 0.2794)
			(stroke
				(width 0.1)
				(type default)
			)
			(layer "F.Fab")
		)
		(fp_line
			(start 0.118364 0.2794)
			(end -0.119634 0.2794)
			(stroke
				(width 0.1)
				(type default)
			)
			(layer "F.Fab")
		)
		(fp_line
			(start -0.118364 -0.2794)
			(end 0.118872 -0.2794)
			(stroke
				(width 0.1)
				(type default)
			)
			(layer "F.Fab")
		)
		(fp_line
			(start -0.118364 -0.307086)
			(end -0.118364 -0.2794)
			(stroke
				(width 0.1)
				(type default)
			)
			(layer "F.Fab")
		)
		(fp_line
			(start -0.119634 0.30607)
			(end -0.681736 0.30607)
			(stroke
				(width 0.1)
				(type default)
			)
			(layer "F.Fab")
		)
		(fp_line
			(start -0.119634 0.2794)
			(end -0.119634 0.30607)
			(stroke
				(width 0.1)
				(type default)
			)
			(layer "F.Fab")
		)
		(fp_line
			(start -0.681736 0.30607)
			(end -0.681736 -0.307086)
			(stroke
				(width 0.1)
				(type default)
			)
			(layer "F.Fab")
		)
		(fp_line
			(start -0.681736 -0.307086)
			(end -0.118364 -0.307086)
			(stroke
				(width 0.1)
				(type default)
			)
			(layer "F.Fab")
		)
		(pad "1" smd rect
			(at -0.40005 0)
			(size 0.4572 0.508)
			(layers "F.Cu" "F.Mask" "F.Paste")
			(net "P1V8_CPU0_RT_1D")
		)
		(pad "2" smd rect
			(at 0.40005 0)
			(size 0.4572 0.508)
			(layers "F.Cu" "F.Mask" "F.Paste")
			(net "P1V8_CPU0_RT3_1A_1D")
		)
	)
)
